# SCM (Grand Teton) — schematic netlist excerpt (pin names and nets, part order shuffled) for the footprints in the layout excerpt that follows; sources: Cadence DE-HDL packaged netlist, KiCad conversion of 12092022_DA0F0TMDCD0_F0T_Management_Board_D_brd_V3_OCP.brd

R412  Q_RES  100 1% CHIP  pkg 0402LF  page 26 : A = FRU_E1 ; B = GND
R350  Q_RES  120 1% EMPTY  pkg 0402LF  page 20 : A = GND ; B = M_BMC_DDR4_MBG1

(kicad_pcb
	(version 20260206)
	(generator "pcbnew")
	(generator_version "10.0")
	(general
		(thickness 1.6)
		(legacy_teardrops no)
	)
	(paper "A4")
	(title_block
		(title "12092022_DA0F0TMDCD0_F0T_Management_Board_D_brd_V3_OCP.brd")
		(comment 1 "Grand Teton / footprints 1415-1416 of 1440")
	)
	(layers
		(0 "F.Cu" signal "TOP")
		(4 "In1.Cu" signal "GND")
		(6 "In2.Cu" signal "IN1")
		(8 "In3.Cu" signal "GND1")
		(10 "In4.Cu" signal "IN2")
		(12 "In5.Cu" signal "VCC")
		(14 "In6.Cu" signal "VCC1")
		(16 "In7.Cu" signal "IN3")
		(18 "In8.Cu" signal "GND2")
		(20 "In9.Cu" signal "IN4")
		(22 "In10.Cu" signal "GND3")
		(2 "B.Cu" signal "BOTTOM")
		(9 "F.Adhes" user "F.Adhesive")
		(11 "B.Adhes" user "B.Adhesive")
		(13 "F.Paste" user "Package Geometry/Pastemask Top")
		(15 "B.Paste" user "Package Geometry/Pastemask Bottom")
		(5 "F.SilkS" user "Ref Des/Silkscreen Top")
		(7 "B.SilkS" user "Ref Des/Silkscreen Bottom")
		(1 "F.Mask" user "Board Geometry/Soldermask Top")
		(3 "B.Mask" user "Board Geometry/Soldermask Bottom")
		(17 "Dwgs.User" user "User.Drawings")
		(19 "Cmts.User" user "User.Comments")
		(21 "Eco1.User" user "User.Eco1")
		(23 "Eco2.User" user "User.Eco2")
		(25 "Edge.Cuts" user "Board Geometry/Outline")
		(27 "Margin" user)
		(31 "F.CrtYd" user "Package Geometry/Place Bound Top")
		(29 "B.CrtYd" user "Package Geometry/Place Bound Bottom")
		(35 "F.Fab" user "Ref Des/Assembly Top")
		(33 "B.Fab" user "Ref Des/Assembly Bottom")
	)
	(footprint ""
		(layer "B.Cu")
		(at 83.16722 -47.602394)
		(property "Reference" "R350"
			(at 0 0 0)
			(layer "B.SilkS")
			(hide yes)
			(effects
				(font
					(size 1.27 1.27)
				)
				(justify mirror)
			)
		)
		(property "Value" ""
			(at 0 0 0)
			(layer "B.Fab")
			(effects
				(font
					(size 1.27 1.27)
				)
				(justify mirror)
			)
		)
		(duplicate_pad_numbers_are_jumpers no)
		(fp_line
			(start -0.7874 -0.4064)
			(end -0.7874 0.4064)
			(stroke
				(width 0.1524)
				(type default)
			)
			(layer "B.SilkS")
		)
		(fp_line
			(start -0.7874 0.4064)
			(end 0.7874 0.4064)
			(stroke
				(width 0.1524)
				(type default)
			)
			(layer "B.SilkS")
		)
		(fp_line
			(start 0.7874 -0.4064)
			(end -0.7874 -0.4064)
			(stroke
				(width 0.1524)
				(type default)
			)
			(layer "B.SilkS")
		)
		(fp_line
			(start 0.7874 0.4064)
			(end 0.7874 -0.4064)
			(stroke
				(width 0.1524)
				(type default)
			)
			(layer "B.SilkS")
		)
		(fp_line
			(start -0.67945 -0.3048)
			(end -0.67945 0.3048)
			(stroke
				(width 0.1)
				(type default)
			)
			(layer "B.Fab")
		)
		(fp_line
			(start -0.67945 0.3048)
			(end -0.120396 0.3048)
			(stroke
				(width 0.1)
				(type default)
			)
			(layer "B.Fab")
		)
		(fp_line
			(start -0.12065 -0.3048)
			(end -0.67945 -0.3048)
			(stroke
				(width 0.1)
				(type default)
			)
			(layer "B.Fab")
		)
		(fp_line
			(start -0.12065 -0.2794)
			(end -0.12065 -0.3048)
			(stroke
				(width 0.1)
				(type default)
			)
			(layer "B.Fab")
		)
		(fp_line
			(start -0.120396 0.2794)
			(end 0.12065 0.2794)
			(stroke
				(width 0.1)
				(type default)
			)
			(layer "B.Fab")
		)
		(fp_line
			(start -0.120396 0.3048)
			(end -0.120396 0.2794)
			(stroke
				(width 0.1)
				(type default)
			)
			(layer "B.Fab")
		)
		(fp_line
			(start 0.12065 -0.305054)
			(end 0.12065 -0.2794)
			(stroke
				(width 0.1)
				(type default)
			)
			(layer "B.Fab")
		)
		(fp_line
			(start 0.12065 -0.2794)
			(end -0.12065 -0.2794)
			(stroke
				(width 0.1)
				(type default)
			)
			(layer "B.Fab")
		)
		(fp_line
			(start 0.12065 0.2794)
			(end 0.12065 0.3048)
			(stroke
				(width 0.1)
				(type default)
			)
			(layer "B.Fab")
		)
		(fp_line
			(start 0.12065 0.3048)
			(end 0.67945 0.3048)
			(stroke
				(width 0.1)
				(type default)
			)
			(layer "B.Fab")
		)
		(fp_line
			(start 0.67945 -0.305054)
			(end 0.12065 -0.305054)
			(stroke
				(width 0.1)
				(type default)
			)
			(layer "B.Fab")
		)
		(fp_line
			(start 0.67945 0.3048)
			(end 0.67945 -0.305054)
			(stroke
				(width 0.1)
				(type default)
			)
			(layer "B.Fab")
		)
		(pad "1" smd circle
			(at 0.40005 0 180)
			(size 0 0)
			(layers "B.Cu" "B.Mask" "B.Paste")
			(net "GND")
		)
		(pad "2" smd circle
			(at -0.40005 0 180)
			(size 0 0)
			(layers "B.Cu" "B.Mask" "B.Paste")
			(net "M_BMC_DDR4_MBG1")
		)
	)
	(footprint ""
		(layer "B.Cu")
		(at 83.283552 -27.607768 180)
		(property "Reference" "R412"
			(at 0 0 0)
			(layer "B.SilkS")
			(hide yes)
			(effects
				(font
					(size 1.27 1.27)
				)
				(justify mirror)
			)
		)
		(property "Value" ""
			(at 0 0 0)
			(layer "B.Fab")
			(effects
				(font
					(size 1.27 1.27)
				)
				(justify mirror)
			)
		)
		(duplicate_pad_numbers_are_jumpers no)
		(fp_line
			(start 0.7874 0.4064)
			(end 0.7874 -0.4064)
			(stroke
				(width 0.1524)
				(type default)
			)
			(layer "B.SilkS")
		)
		(fp_line
			(start 0.7874 -0.4064)
			(end -0.7874 -0.4064)
			(stroke
				(width 0.1524)
				(type default)
			)
			(layer "B.SilkS")
		)
		(fp_line
			(start -0.7874 0.4064)
			(end 0.7874 0.4064)
			(stroke
				(width 0.1524)
				(type default)
			)
			(layer "B.SilkS")
		)
		(fp_line
			(start -0.7874 -0.4064)
			(end -0.7874 0.4064)
			(stroke
				(width 0.1524)
				(type default)
			)
			(layer "B.SilkS")
		)
		(fp_line
			(start 0.67945 0.3048)
			(end 0.67945 -0.305054)
			(stroke
				(width 0.1)
				(type default)
			)
			(layer "B.Fab")
		)
		(fp_line
			(start 0.67945 -0.305054)
			(end 0.12065 -0.305054)
			(stroke
				(width 0.1)
				(type default)
			)
			(layer "B.Fab")
		)
		(fp_line
			(start 0.12065 0.3048)
			(end 0.67945 0.3048)
			(stroke
				(width 0.1)
				(type default)
			)
			(layer "B.Fab")
		)
		(fp_line
			(start 0.12065 0.2794)
			(end 0.12065 0.3048)
			(stroke
				(width 0.1)
				(type default)
			)
			(layer "B.Fab")
		)
		(fp_line
			(start 0.12065 -0.2794)
			(end -0.12065 -0.2794)
			(stroke
				(width 0.1)
				(type default)
			)
			(layer "B.Fab")
		)
		(fp_line
			(start 0.12065 -0.305054)
			(end 0.12065 -0.2794)
			(stroke
				(width 0.1)
				(type default)
			)
			(layer "B.Fab")
		)
		(fp_line
			(start -0.120396 0.3048)
			(end -0.120396 0.2794)
			(stroke
				(width 0.1)
				(type default)
			)
			(layer "B.Fab")
		)
		(fp_line
			(start -0.120396 0.2794)
			(end 0.12065 0.2794)
			(stroke
				(width 0.1)
				(type default)
			)
			(layer "B.Fab")
		)
		(fp_line
			(start -0.12065 -0.2794)
			(end -0.12065 -0.3048)
			(stroke
				(width 0.1)
				(type default)
			)
			(layer "B.Fab")
		)
		(fp_line
			(start -0.12065 -0.3048)
			(end -0.67945 -0.3048)
			(stroke
				(width 0.1)
				(type default)
			)
			(layer "B.Fab")
		)
		(fp_line
			(start -0.67945 0.3048)
			(end -0.120396 0.3048)
			(stroke
				(width 0.1)
				(type default)
			)
			(layer "B.Fab")
		)
		(fp_line
			(start -0.67945 -0.3048)
			(end -0.67945 0.3048)
			(stroke
				(width 0.1)
				(type default)
			)
			(layer "B.Fab")
		)
		(pad "1" smd circle
			(at 0.40005 0)
			(size 0 0)
			(layers "B.Cu" "B.Mask" "B.Paste")
			(net "FRU_E1")
		)
		(pad "2" smd circle
			(at -0.40005 0)
			(size 0 0)
			(layers "B.Cu" "B.Mask" "B.Paste")
			(net "GND")
		)
	)
)
